# NUC Computer Cluster Power Breakout HW — assets/stackup.csv
Name;Type;Material;Thickness[mm];Constant
F.Mask;Top Solder Mask;;0.01;
F.Cu;copper;;0.035;
dielectric 1;core;FR4;0.48;4.5
In1.Cu;copper;;0.035;
dielectric 2;prepreg;FR4;0.48;4.5
In2.Cu;copper;;0.035;
dielectric 3;core;FR4;0.48;4.5
B.Cu;copper;;0.035;
B.Mask;Bottom Solder Mask;;0.01;
